# T6G (Grand Teton) — schematic netlist excerpt (pin names and nets, part order shuffled) for the footprints in the layout excerpt that follows; sources: Cadence DE-HDL packaged netlist, KiCad conversion of 04192023_DAF0TMB3IC0_F0TG_MB_C_brd_V02_OCP.brd

C8009  Q_CAP  0.1UF 25V 10% X7R  pkg 0402  page 142 : A = P3V3_OCP_V3_2_R ; B = GND
C7005  Q_CAPP  470UF 2.5V 20% SPCAP  pkg SMLF  page 345 : A = P0V9_CPU1_RT_2D ; B = GND

(kicad_pcb
	(version 20260206)
	(generator "pcbnew")
	(generator_version "10.0")
	(general
		(thickness 1.6)
		(legacy_teardrops no)
	)
	(paper "A4")
	(title_block
		(title "04192023_DAF0TMB3IC0_F0TG_MB_C_brd_V02_OCP.brd")
		(comment 1 "Grand Teton / footprints 4897-4898 of 8354")
	)
	(layers
		(0 "F.Cu" signal "TOP")
		(4 "In1.Cu" signal "GND")
		(6 "In2.Cu" signal "IN1")
		(8 "In3.Cu" signal "GND1")
		(10 "In4.Cu" signal "IN2")
		(12 "In5.Cu" signal "GND2")
		(14 "In6.Cu" signal "IN3")
		(16 "In7.Cu" signal "GND3")
		(18 "In8.Cu" signal "VCC")
		(20 "In9.Cu" signal "VCC1")
		(22 "In10.Cu" signal "GND4")
		(24 "In11.Cu" signal "IN4")
		(26 "In12.Cu" signal "GND5")
		(28 "In13.Cu" signal "IN5")
		(30 "In14.Cu" signal "GND6")
		(32 "In15.Cu" signal "IN6")
		(34 "In16.Cu" signal "GND7")
		(2 "B.Cu" signal "BOTTOM")
		(9 "F.Adhes" user "F.Adhesive")
		(11 "B.Adhes" user "B.Adhesive")
		(13 "F.Paste" user "Package Geometry/Pastemask Top")
		(15 "B.Paste" user "Package Geometry/Pastemask Bottom")
		(5 "F.SilkS" user "Ref Des/Silkscreen Top")
		(7 "B.SilkS" user "Ref Des/Silkscreen Bottom")
		(1 "F.Mask" user "Board Geometry/Soldermask Top")
		(3 "B.Mask" user "Board Geometry/Soldermask Bottom")
		(17 "Dwgs.User" user "User.Drawings")
		(19 "Cmts.User" user "User.Comments")
		(21 "Eco1.User" user "User.Eco1")
		(23 "Eco2.User" user "User.Eco2")
		(25 "Edge.Cuts" user "Board Geometry/Outline")
		(27 "Margin" user)
		(31 "F.CrtYd" user "Package Geometry/Place Bound Top")
		(29 "B.CrtYd" user "Package Geometry/Place Bound Bottom")
		(35 "F.Fab" user "Ref Des/Assembly Top")
		(33 "B.Fab" user "Ref Des/Assembly Bottom")
	)
	(footprint ""
		(layer "F.Cu")
		(at 134.474712 -400.76882 180)
		(property "Reference" "C7005"
			(at -1.133856 -2.910332 0)
			(unlocked yes)
			(layer "F.SilkS")
			(effects
				(font
					(size 0.7874 0.5842)
					(thickness 0.1524)
				)
				(justify left)
			)
		)
		(property "Value" ""
			(at 0 0 180)
			(layer "F.Fab")
			(effects
				(font
					(size 1.27 1.27)
				)
			)
		)
		(duplicate_pad_numbers_are_jumpers no)
		(fp_line
			(start 4.53898 2.15011)
			(end -4.53898 2.15011)
			(stroke
				(width 0.1524)
				(type default)
			)
			(layer "F.SilkS")
		)
		(fp_line
			(start 4.53898 -2.15011)
			(end 4.53898 2.15011)
			(stroke
				(width 0.1524)
				(type default)
			)
			(layer "F.SilkS")
		)
		(fp_line
			(start -4.53898 2.15011)
			(end -4.53898 -2.15011)
			(stroke
				(width 0.1524)
				(type default)
			)
			(layer "F.SilkS")
		)
		(fp_line
			(start -4.53898 -2.15011)
			(end 4.53898 -2.15011)
			(stroke
				(width 0.1524)
				(type default)
			)
			(layer "F.SilkS")
		)
		(fp_line
			(start -4.53898 -2.150618)
			(end -4.539742 2.152142)
			(stroke
				(width 0.1524)
				(type default)
			)
			(layer "F.SilkS")
		)
		(fp_line
			(start -4.69138 -2.150618)
			(end -4.692396 2.161032)
			(stroke
				(width 0.1524)
				(type default)
			)
			(layer "F.SilkS")
		)
		(fp_line
			(start -4.83108 2.150364)
			(end -4.447794 2.149348)
			(stroke
				(width 0.1524)
				(type default)
			)
			(layer "F.SilkS")
		)
		(fp_line
			(start -4.84378 -2.150618)
			(end -4.53898 -2.150618)
			(stroke
				(width 0.1524)
				(type default)
			)
			(layer "F.SilkS")
		)
		(fp_line
			(start -4.84378 -2.150618)
			(end -4.842256 2.163064)
			(stroke
				(width 0.1524)
				(type default)
			)
			(layer "F.SilkS")
		)
		(fp_line
			(start 3.64998 2.15011)
			(end -3.64998 2.15011)
			(stroke
				(width 0.1)
				(type default)
			)
			(layer "F.Fab")
		)
		(fp_line
			(start 3.64998 -2.15011)
			(end 3.64998 2.15011)
			(stroke
				(width 0.1)
				(type default)
			)
			(layer "F.Fab")
		)
		(fp_line
			(start -3.64998 2.15011)
			(end -3.64998 -2.15011)
			(stroke
				(width 0.1)
				(type default)
			)
			(layer "F.Fab")
		)
		(fp_line
			(start -3.64998 -2.15011)
			(end 3.64998 -2.15011)
			(stroke
				(width 0.1)
				(type default)
			)
			(layer "F.Fab")
		)
		(fp_text user "-"
			(at 4.869434 -0.582168 180)
			(unlocked yes)
			(layer "F.SilkS")
			(effects
				(font
					(size 1.905 1.4224)
					(thickness 0.1524)
				)
				(justify left)
			)
		)
		(fp_text user "+"
			(at -6.075172 -1.660398 180)
			(unlocked yes)
			(layer "F.SilkS")
			(effects
				(font
					(size 1.905 1.4224)
					(thickness 0.1524)
				)
				(justify left)
			)
		)
		(fp_text user "-"
			(at 4.313174 -0.094488 180)
			(unlocked yes)
			(layer "F.Fab")
			(effects
				(font
					(size 1.905 1.4224)
					(thickness 0.1524)
				)
				(justify left)
			)
		)
		(fp_text user "+"
			(at -6.214872 -0.337058 180)
			(unlocked yes)
			(layer "F.Fab")
			(effects
				(font
					(size 1.905 1.4224)
					(thickness 0.1524)
				)
				(justify left)
			)
		)
		(pad "1" smd rect
			(at -3.199892 0 180)
			(size 2.413 2.8194)
			(layers "F.Cu" "F.Mask" "F.Paste")
			(net "P0V9_CPU1_RT_2D")
		)
		(pad "2" smd rect
			(at 3.199892 0 180)
			(size 2.413 2.8194)
			(layers "F.Cu" "F.Mask" "F.Paste")
			(net "GND")
		)
	)
	(footprint ""
		(layer "F.Cu")
		(at 79.248 -61.214 180)
		(property "Reference" "C8009"
			(at 0 0 180)
			(layer "F.SilkS")
			(hide yes)
			(effects
				(font
					(size 1.27 1.27)
				)
			)
		)
		(property "Value" ""
			(at 0 0 180)
			(layer "F.Fab")
			(effects
				(font
					(size 1.27 1.27)
				)
			)
		)
		(duplicate_pad_numbers_are_jumpers no)
		(fp_line
			(start 0.7874 0.4064)
			(end -0.7874 0.4064)
			(stroke
				(width 0.1524)
				(type default)
			)
			(layer "F.SilkS")
		)
		(fp_line
			(start 0.7874 -0.4064)
			(end 0.7874 0.4064)
			(stroke
				(width 0.1524)
				(type default)
			)
			(layer "F.SilkS")
		)
		(fp_line
			(start -0.7874 0.4064)
			(end -0.7874 -0.4064)
			(stroke
				(width 0.1524)
				(type default)
			)
			(layer "F.SilkS")
		)
		(fp_line
			(start -0.7874 -0.4064)
			(end 0.7874 -0.4064)
			(stroke
				(width 0.1524)
				(type default)
			)
			(layer "F.SilkS")
		)
		(fp_line
			(start 0.67945 0.3048)
			(end 0.120396 0.3048)
			(stroke
				(width 0.1)
				(type default)
			)
			(layer "F.Fab")
		)
		(fp_line
			(start 0.67945 -0.3048)
			(end 0.67945 0.3048)
			(stroke
				(width 0.1)
				(type default)
			)
			(layer "F.Fab")
		)
		(fp_line
			(start 0.12065 -0.2794)
			(end 0.12065 -0.3048)
			(stroke
				(width 0.1)
				(type default)
			)
			(layer "F.Fab")
		)
		(fp_line
			(start 0.12065 -0.3048)
			(end 0.67945 -0.3048)
			(stroke
				(width 0.1)
				(type default)
			)
			(layer "F.Fab")
		)
		(fp_line
			(start 0.120396 0.3048)
			(end 0.120396 0.2794)
			(stroke
				(width 0.1)
				(type default)
			)
			(layer "F.Fab")
		)
		(fp_line
			(start 0.120396 0.2794)
			(end -0.12065 0.2794)
			(stroke
				(width 0.1)
				(type default)
			)
			(layer "F.Fab")
		)
		(fp_line
			(start -0.12065 0.3048)
			(end -0.67945 0.3048)
			(stroke
				(width 0.1)
				(type default)
			)
			(layer "F.Fab")
		)
		(fp_line
			(start -0.12065 0.2794)
			(end -0.12065 0.3048)
			(stroke
				(width 0.1)
				(type default)
			)
			(layer "F.Fab")
		)
		(fp_line
			(start -0.12065 -0.2794)
			(end 0.12065 -0.2794)
			(stroke
				(width 0.1)
				(type default)
			)
			(layer "F.Fab")
		)
		(fp_line
			(start -0.12065 -0.305054)
			(end -0.12065 -0.2794)
			(stroke
				(width 0.1)
				(type default)
			)
			(layer "F.Fab")
		)
		(fp_line
			(start -0.67945 0.3048)
			(end -0.67945 -0.305054)
			(stroke
				(width 0.1)
				(type default)
			)
			(layer "F.Fab")
		)
		(fp_line
			(start -0.67945 -0.305054)
			(end -0.12065 -0.305054)
			(stroke
				(width 0.1)
				(type default)
			)
			(layer "F.Fab")
		)
		(pad "1" smd circle
			(at -0.40005 0 180)
			(size 0 0)
			(layers "F.Cu" "F.Mask" "F.Paste")
			(net "P3V3_OCP_V3_2_R")
		)
		(pad "2" smd circle
			(at 0.40005 0 180)
			(size 0 0)
			(layers "F.Cu" "F.Mask" "F.Paste")
			(net "GND")
		)
	)
)
